(kicad_pcb
	(version 20260206)
	(generator "pcbnew")
	(generator_version "10.0")
	(general
		(thickness 1.6)
		(legacy_teardrops no)
	)
	(paper "A4")
	(title_block
		(title "01162023_DA0F0TEBIF0_F0T_Expander_BD_F_brd_V02_OCP.brd")
		(comment 1 "Grand Teton / footprints 669-676 of 9728")
	)
	(layers
		(0 "F.Cu" signal "TOP")
		(4 "In1.Cu" signal "GND")
		(6 "In2.Cu" signal "VCC")
		(8 "In3.Cu" signal "VCC1")
		(10 "In4.Cu" signal "GND1")
		(12 "In5.Cu" signal "IN1")
		(14 "In6.Cu" signal "GND2")
		(16 "In7.Cu" signal "IN2")
		(18 "In8.Cu" signal "GND3")
		(20 "In9.Cu" signal "IN3")
		(22 "In10.Cu" signal "GND4")
		(24 "In11.Cu" signal "IN4")
		(26 "In12.Cu" signal "GND5")
		(28 "In13.Cu" signal "IN5")
		(30 "In14.Cu" signal "GND6")
		(32 "In15.Cu" signal "IN6")
		(34 "In16.Cu" signal "GND7")
		(2 "B.Cu" signal "BOTTOM")
		(9 "F.Adhes" user "F.Adhesive")
		(11 "B.Adhes" user "B.Adhesive")
		(13 "F.Paste" user "Package Geometry/Pastemask Top")
		(15 "B.Paste" user "Package Geometry/Pastemask Bottom")
		(5 "F.SilkS" user "Ref Des/Silkscreen Top")
		(7 "B.SilkS" user "Ref Des/Silkscreen Bottom")
		(1 "F.Mask" user "Board Geometry/Soldermask Top")
		(3 "B.Mask" user "Board Geometry/Soldermask Bottom")
		(17 "Dwgs.User" user "User.Drawings")
		(19 "Cmts.User" user "User.Comments")
		(21 "Eco1.User" user "User.Eco1")
		(23 "Eco2.User" user "User.Eco2")
		(25 "Edge.Cuts" user "Board Geometry/Outline")
		(27 "Margin" user)
		(31 "F.CrtYd" user "Package Geometry/Place Bound Top")
		(29 "B.CrtYd" user "Package Geometry/Place Bound Bottom")
		(35 "F.Fab" user "Ref Des/Assembly Top")
		(33 "B.Fab" user "Ref Des/Assembly Bottom")
	)
	(footprint ""
		(layer "F.Cu")
		(at 438.318148 -306.074572 90)
		(property "Reference" "R1440"
			(at 0 0 90)
			(layer "F.SilkS")
			(hide yes)
			(effects
				(font
					(size 1.27 1.27)
				)
			)
		)
		(property "Value" ""
			(at 0 0 90)
			(layer "F.Fab")
			(effects
				(font
					(size 1.27 1.27)
				)
			)
		)
		(duplicate_pad_numbers_are_jumpers no)
		(fp_line
			(start 0.7874 -0.4064)
			(end 0.7874 0.4064)
			(stroke
				(width 0.1524)
				(type default)
			)
			(layer "F.SilkS")
		)
		(fp_line
			(start -0.7874 -0.4064)
			(end 0.7874 -0.4064)
			(stroke
				(width 0.1524)
				(type default)
			)
			(layer "F.SilkS")
		)
		(fp_line
			(start 0.7874 0.4064)
			(end -0.7874 0.4064)
			(stroke
				(width 0.1524)
				(type default)
			)
			(layer "F.SilkS")
		)
		(fp_line
			(start -0.7874 0.4064)
			(end -0.7874 -0.4064)
			(stroke
				(width 0.1524)
				(type default)
			)
			(layer "F.SilkS")
		)
		(fp_line
			(start -0.12065 -0.305054)
			(end -0.12065 -0.2794)
			(stroke
				(width 0.1)
				(type default)
			)
			(layer "F.Fab")
		)
		(fp_line
			(start -0.67945 -0.305054)
			(end -0.12065 -0.305054)
			(stroke
				(width 0.1)
				(type default)
			)
			(layer "F.Fab")
		)
		(fp_line
			(start 0.67945 -0.3048)
			(end 0.67945 0.3048)
			(stroke
				(width 0.1)
				(type default)
			)
			(layer "F.Fab")
		)
		(fp_line
			(start 0.12065 -0.3048)
			(end 0.67945 -0.3048)
			(stroke
				(width 0.1)
				(type default)
			)
			(layer "F.Fab")
		)
		(fp_line
			(start 0.12065 -0.2794)
			(end 0.12065 -0.3048)
			(stroke
				(width 0.1)
				(type default)
			)
			(layer "F.Fab")
		)
		(fp_line
			(start -0.12065 -0.2794)
			(end 0.12065 -0.2794)
			(stroke
				(width 0.1)
				(type default)
			)
			(layer "F.Fab")
		)
		(fp_line
			(start 0.120396 0.2794)
			(end -0.12065 0.2794)
			(stroke
				(width 0.1)
				(type default)
			)
			(layer "F.Fab")
		)
		(fp_line
			(start -0.12065 0.2794)
			(end -0.12065 0.3048)
			(stroke
				(width 0.1)
				(type default)
			)
			(layer "F.Fab")
		)
		(fp_line
			(start 0.67945 0.3048)
			(end 0.120396 0.3048)
			(stroke
				(width 0.1)
				(type default)
			)
			(layer "F.Fab")
		)
		(fp_line
			(start 0.120396 0.3048)
			(end 0.120396 0.2794)
			(stroke
				(width 0.1)
				(type default)
			)
			(layer "F.Fab")
		)
		(fp_line
			(start -0.12065 0.3048)
			(end -0.67945 0.3048)
			(stroke
				(width 0.1)
				(type default)
			)
			(layer "F.Fab")
		)
		(fp_line
			(start -0.67945 0.3048)
			(end -0.67945 -0.305054)
			(stroke
				(width 0.1)
				(type default)
			)
			(layer "F.Fab")
		)
		(pad "1" smd circle
			(at -0.40005 0 90)
			(size 0 0)
			(layers "F.Cu" "F.Mask" "F.Paste")
			(net "PEX3_SPARE3")
		)
		(pad "2" smd circle
			(at 0.40005 0 90)
			(size 0 0)
			(layers "F.Cu" "F.Mask" "F.Paste")
			(net "P1V8_PEX")
		)
	)
	(footprint ""
		(layer "F.Cu")
		(at 212.422994 -222.399352 90)
		(property "Reference" "R4885"
			(at 0 0 90)
			(layer "F.SilkS")
			(hide yes)
			(effects
				(font
					(size 1.27 1.27)
				)
			)
		)
		(property "Value" ""
			(at 0 0 90)
			(layer "F.Fab")
			(effects
				(font
					(size 1.27 1.27)
				)
			)
		)
		(duplicate_pad_numbers_are_jumpers no)
		(fp_line
			(start 0.7874 -0.4064)
			(end 0.7874 0.4064)
			(stroke
				(width 0.1524)
				(type default)
			)
			(layer "F.SilkS")
		)
		(fp_line
			(start -0.7874 -0.4064)
			(end 0.7874 -0.4064)
			(stroke
				(width 0.1524)
				(type default)
			)
			(layer "F.SilkS")
		)
		(fp_line
			(start 0.7874 0.4064)
			(end -0.7874 0.4064)
			(stroke
				(width 0.1524)
				(type default)
			)
			(layer "F.SilkS")
		)
		(fp_line
			(start -0.7874 0.4064)
			(end -0.7874 -0.4064)
			(stroke
				(width 0.1524)
				(type default)
			)
			(layer "F.SilkS")
		)
		(fp_line
			(start -0.12065 -0.305054)
			(end -0.12065 -0.2794)
			(stroke
				(width 0.1)
				(type default)
			)
			(layer "F.Fab")
		)
		(fp_line
			(start -0.67945 -0.305054)
			(end -0.12065 -0.305054)
			(stroke
				(width 0.1)
				(type default)
			)
			(layer "F.Fab")
		)
		(fp_line
			(start 0.67945 -0.3048)
			(end 0.67945 0.3048)
			(stroke
				(width 0.1)
				(type default)
			)
			(layer "F.Fab")
		)
		(fp_line
			(start 0.12065 -0.3048)
			(end 0.67945 -0.3048)
			(stroke
				(width 0.1)
				(type default)
			)
			(layer "F.Fab")
		)
		(fp_line
			(start 0.12065 -0.2794)
			(end 0.12065 -0.3048)
			(stroke
				(width 0.1)
				(type default)
			)
			(layer "F.Fab")
		)
		(fp_line
			(start -0.12065 -0.2794)
			(end 0.12065 -0.2794)
			(stroke
				(width 0.1)
				(type default)
			)
			(layer "F.Fab")
		)
		(fp_line
			(start 0.120396 0.2794)
			(end -0.12065 0.2794)
			(stroke
				(width 0.1)
				(type default)
			)
			(layer "F.Fab")
		)
		(fp_line
			(start -0.12065 0.2794)
			(end -0.12065 0.3048)
			(stroke
				(width 0.1)
				(type default)
			)
			(layer "F.Fab")
		)
		(fp_line
			(start 0.67945 0.3048)
			(end 0.120396 0.3048)
			(stroke
				(width 0.1)
				(type default)
			)
			(layer "F.Fab")
		)
		(fp_line
			(start 0.120396 0.3048)
			(end 0.120396 0.2794)
			(stroke
				(width 0.1)
				(type default)
			)
			(layer "F.Fab")
		)
		(fp_line
			(start -0.12065 0.3048)
			(end -0.67945 0.3048)
			(stroke
				(width 0.1)
				(type default)
			)
			(layer "F.Fab")
		)
		(fp_line
			(start -0.67945 0.3048)
			(end -0.67945 -0.305054)
			(stroke
				(width 0.1)
				(type default)
			)
			(layer "F.Fab")
		)
		(pad "1" smd circle
			(at -0.40005 0 90)
			(size 0 0)
			(layers "F.Cu" "F.Mask" "F.Paste")
			(net "SMB_BIC_I2C9_SSD_MUX_R_SCL")
		)
		(pad "2" smd circle
			(at 0.40005 0 90)
			(size 0 0)
			(layers "F.Cu" "F.Mask" "F.Paste")
			(net "P3V3_AUX")
		)
	)
	(footprint ""
		(layer "F.Cu")
		(at 210.439 -199.263)
		(property "Reference" "C2626"
			(at 0 0 0)
			(layer "F.SilkS")
			(hide yes)
			(effects
				(font
					(size 1.27 1.27)
				)
			)
		)
		(property "Value" ""
			(at 0 0 0)
			(layer "F.Fab")
			(effects
				(font
					(size 1.27 1.27)
				)
			)
		)
		(duplicate_pad_numbers_are_jumpers no)
		(fp_line
			(start -0.7874 -0.4064)
			(end 0.7874 -0.4064)
			(stroke
				(width 0.1524)
				(type default)
			)
			(layer "F.SilkS")
		)
		(fp_line
			(start -0.7874 0.4064)
			(end -0.7874 -0.4064)
			(stroke
				(width 0.1524)
				(type default)
			)
			(layer "F.SilkS")
		)
		(fp_line
			(start 0.7874 -0.4064)
			(end 0.7874 0.4064)
			(stroke
				(width 0.1524)
				(type default)
			)
			(layer "F.SilkS")
		)
		(fp_line
			(start 0.7874 0.4064)
			(end -0.7874 0.4064)
			(stroke
				(width 0.1524)
				(type default)
			)
			(layer "F.SilkS")
		)
		(fp_line
			(start -0.67945 -0.305054)
			(end -0.12065 -0.305054)
			(stroke
				(width 0.1)
				(type default)
			)
			(layer "F.Fab")
		)
		(fp_line
			(start -0.67945 0.3048)
			(end -0.67945 -0.305054)
			(stroke
				(width 0.1)
				(type default)
			)
			(layer "F.Fab")
		)
		(fp_line
			(start -0.12065 -0.305054)
			(end -0.12065 -0.2794)
			(stroke
				(width 0.1)
				(type default)
			)
			(layer "F.Fab")
		)
		(fp_line
			(start -0.12065 -0.2794)
			(end 0.12065 -0.2794)
			(stroke
				(width 0.1)
				(type default)
			)
			(layer "F.Fab")
		)
		(fp_line
			(start -0.12065 0.2794)
			(end -0.12065 0.3048)
			(stroke
				(width 0.1)
				(type default)
			)
			(layer "F.Fab")
		)
		(fp_line
			(start -0.12065 0.3048)
			(end -0.67945 0.3048)
			(stroke
				(width 0.1)
				(type default)
			)
			(layer "F.Fab")
		)
		(fp_line
			(start 0.120396 0.2794)
			(end -0.12065 0.2794)
			(stroke
				(width 0.1)
				(type default)
			)
			(layer "F.Fab")
		)
		(fp_line
			(start 0.120396 0.3048)
			(end 0.120396 0.2794)
			(stroke
				(width 0.1)
				(type default)
			)
			(layer "F.Fab")
		)
		(fp_line
			(start 0.12065 -0.3048)
			(end 0.67945 -0.3048)
			(stroke
				(width 0.1)
				(type default)
			)
			(layer "F.Fab")
		)
		(fp_line
			(start 0.12065 -0.2794)
			(end 0.12065 -0.3048)
			(stroke
				(width 0.1)
				(type default)
			)
			(layer "F.Fab")
		)
		(fp_line
			(start 0.67945 -0.3048)
			(end 0.67945 0.3048)
			(stroke
				(width 0.1)
				(type default)
			)
			(layer "F.Fab")
		)
		(fp_line
			(start 0.67945 0.3048)
			(end 0.120396 0.3048)
			(stroke
				(width 0.1)
				(type default)
			)
			(layer "F.Fab")
		)
		(pad "1" smd circle
			(at -0.40005 0)
			(size 0 0)
			(layers "F.Cu" "F.Mask" "F.Paste")
			(net "GND")
		)
		(pad "2" smd circle
			(at 0.40005 0)
			(size 0 0)
			(layers "F.Cu" "F.Mask" "F.Paste")
			(net "P1V2_AUX")
		)
	)
	(footprint ""
		(layer "F.Cu")
		(at 384.938524 -104.695498)
		(property "Reference" "C690"
			(at 0 0 0)
			(layer "F.SilkS")
			(hide yes)
			(effects
				(font
					(size 1.27 1.27)
				)
			)
		)
		(property "Value" ""
			(at 0 0 0)
			(layer "F.Fab")
			(effects
				(font
					(size 1.27 1.27)
				)
			)
		)
		(duplicate_pad_numbers_are_jumpers no)
		(fp_line
			(start -0.299974 -0.150114)
			(end 0.299974 -0.150114)
			(stroke
				(width 0.1)
				(type default)
			)
			(layer "F.Fab")
		)
		(fp_line
			(start -0.299974 0.150114)
			(end -0.299974 -0.150114)
			(stroke
				(width 0.1)
				(type default)
			)
			(layer "F.Fab")
		)
		(fp_line
			(start 0.299974 -0.150114)
			(end 0.299974 0.150114)
			(stroke
				(width 0.1)
				(type default)
			)
			(layer "F.Fab")
		)
		(fp_line
			(start 0.299974 0.150114)
			(end -0.299974 0.150114)
			(stroke
				(width 0.1)
				(type default)
			)
			(layer "F.Fab")
		)
		(pad "1" smd rect
			(at -0.2667 0)
			(size 0.3048 0.381)
			(layers "F.Cu" "F.Mask" "F.Paste")
			(net "P5E_PEX3_STN1_TX_DN<19>")
		)
		(pad "2" smd rect
			(at 0.2667 0)
			(size 0.3048 0.381)
			(layers "F.Cu" "F.Mask" "F.Paste")
			(net "P5E_PEX3_STN1_TX_C_DN<19>")
		)
	)
	(footprint ""
		(layer "F.Cu")
		(at 206.711296 -226.928426 180)
		(property "Reference" "R5916"
			(at 0 0 180)
			(layer "F.SilkS")
			(hide yes)
			(effects
				(font
					(size 1.27 1.27)
				)
			)
		)
		(property "Value" ""
			(at 0 0 180)
			(layer "F.Fab")
			(effects
				(font
					(size 1.27 1.27)
				)
			)
		)
		(duplicate_pad_numbers_are_jumpers no)
		(fp_line
			(start 0.7874 0.4064)
			(end -0.7874 0.4064)
			(stroke
				(width 0.1524)
				(type default)
			)
			(layer "F.SilkS")
		)
		(fp_line
			(start 0.7874 -0.4064)
			(end 0.7874 0.4064)
			(stroke
				(width 0.1524)
				(type default)
			)
			(layer "F.SilkS")
		)
		(fp_line
			(start -0.7874 0.4064)
			(end -0.7874 -0.4064)
			(stroke
				(width 0.1524)
				(type default)
			)
			(layer "F.SilkS")
		)
		(fp_line
			(start -0.7874 -0.4064)
			(end 0.7874 -0.4064)
			(stroke
				(width 0.1524)
				(type default)
			)
			(layer "F.SilkS")
		)
		(fp_line
			(start 0.67945 0.3048)
			(end 0.120396 0.3048)
			(stroke
				(width 0.1)
				(type default)
			)
			(layer "F.Fab")
		)
		(fp_line
			(start 0.67945 -0.3048)
			(end 0.67945 0.3048)
			(stroke
				(width 0.1)
				(type default)
			)
			(layer "F.Fab")
		)
		(fp_line
			(start 0.12065 -0.2794)
			(end 0.12065 -0.3048)
			(stroke
				(width 0.1)
				(type default)
			)
			(layer "F.Fab")
		)
		(fp_line
			(start 0.12065 -0.3048)
			(end 0.67945 -0.3048)
			(stroke
				(width 0.1)
				(type default)
			)
			(layer "F.Fab")
		)
		(fp_line
			(start 0.120396 0.3048)
			(end 0.120396 0.2794)
			(stroke
				(width 0.1)
				(type default)
			)
			(layer "F.Fab")
		)
		(fp_line
			(start 0.120396 0.2794)
			(end -0.12065 0.2794)
			(stroke
				(width 0.1)
				(type default)
			)
			(layer "F.Fab")
		)
		(fp_line
			(start -0.12065 0.3048)
			(end -0.67945 0.3048)
			(stroke
				(width 0.1)
				(type default)
			)
			(layer "F.Fab")
		)
		(fp_line
			(start -0.12065 0.2794)
			(end -0.12065 0.3048)
			(stroke
				(width 0.1)
				(type default)
			)
			(layer "F.Fab")
		)
		(fp_line
			(start -0.12065 -0.2794)
			(end 0.12065 -0.2794)
			(stroke
				(width 0.1)
				(type default)
			)
			(layer "F.Fab")
		)
		(fp_line
			(start -0.12065 -0.305054)
			(end -0.12065 -0.2794)
			(stroke
				(width 0.1)
				(type default)
			)
			(layer "F.Fab")
		)
		(fp_line
			(start -0.67945 0.3048)
			(end -0.67945 -0.305054)
			(stroke
				(width 0.1)
				(type default)
			)
			(layer "F.Fab")
		)
		(fp_line
			(start -0.67945 -0.305054)
			(end -0.12065 -0.305054)
			(stroke
				(width 0.1)
				(type default)
			)
			(layer "F.Fab")
		)
		(pad "1" smd circle
			(at -0.40005 0 180)
			(size 0 0)
			(layers "F.Cu" "F.Mask" "F.Paste")
			(net "P3V3_AUX")
		)
		(pad "2" smd circle
			(at 0.40005 0 180)
			(size 0 0)
			(layers "F.Cu" "F.Mask" "F.Paste")
			(net "PU_BIC_UART_SEL")
		)
	)
	(footprint ""
		(layer "F.Cu")
		(at 415.487612 -350.098614 90)
		(property "Reference" "C2445"
			(at 0 0 90)
			(layer "F.SilkS")
			(hide yes)
			(effects
				(font
					(size 1.27 1.27)
				)
			)
		)
		(property "Value" ""
			(at 0 0 90)
			(layer "F.Fab")
			(effects
				(font
					(size 1.27 1.27)
				)
			)
		)
		(duplicate_pad_numbers_are_jumpers no)
		(fp_line
			(start 0.299974 -0.150114)
			(end 0.299974 0.150114)
			(stroke
				(width 0.1)
				(type default)
			)
			(layer "F.Fab")
		)
		(fp_line
			(start -0.299974 -0.150114)
			(end 0.299974 -0.150114)
			(stroke
				(width 0.1)
				(type default)
			)
			(layer "F.Fab")
		)
		(fp_line
			(start 0.299974 0.150114)
			(end -0.299974 0.150114)
			(stroke
				(width 0.1)
				(type default)
			)
			(layer "F.Fab")
		)
		(fp_line
			(start -0.299974 0.150114)
			(end -0.299974 -0.150114)
			(stroke
				(width 0.1)
				(type default)
			)
			(layer "F.Fab")
		)
		(pad "1" smd rect
			(at -0.2667 0 90)
			(size 0.3048 0.381)
			(layers "F.Cu" "F.Mask" "F.Paste")
			(net "P5E_PEX3_STN4_TX_DP<76>")
		)
		(pad "2" smd rect
			(at 0.2667 0 90)
			(size 0.3048 0.381)
			(layers "F.Cu" "F.Mask" "F.Paste")
			(net "P5E_PEX3_STN4_TX_C_DP<76>")
		)
	)
	(footprint ""
		(layer "F.Cu")
		(at 396.03426 -350.098614 90)
		(property "Reference" "C752"
			(at 0 0 90)
			(layer "F.SilkS")
			(hide yes)
			(effects
				(font
					(size 1.27 1.27)
				)
			)
		)
		(property "Value" ""
			(at 0 0 90)
			(layer "F.Fab")
			(effects
				(font
					(size 1.27 1.27)
				)
			)
		)
		(duplicate_pad_numbers_are_jumpers no)
		(fp_line
			(start 0.299974 -0.150114)
			(end 0.299974 0.150114)
			(stroke
				(width 0.1)
				(type default)
			)
			(layer "F.Fab")
		)
		(fp_line
			(start -0.299974 -0.150114)
			(end 0.299974 -0.150114)
			(stroke
				(width 0.1)
				(type default)
			)
			(layer "F.Fab")
		)
		(fp_line
			(start 0.299974 0.150114)
			(end -0.299974 0.150114)
			(stroke
				(width 0.1)
				(type default)
			)
			(layer "F.Fab")
		)
		(fp_line
			(start -0.299974 0.150114)
			(end -0.299974 -0.150114)
			(stroke
				(width 0.1)
				(type default)
			)
			(layer "F.Fab")
		)
		(pad "1" smd rect
			(at -0.2667 0 90)
			(size 0.3048 0.381)
			(layers "F.Cu" "F.Mask" "F.Paste")
			(net "P5E_PEX3_STN5_TX_DP<84>")
		)
		(pad "2" smd rect
			(at 0.2667 0 90)
			(size 0.3048 0.381)
			(layers "F.Cu" "F.Mask" "F.Paste")
			(net "P5E_PEX3_STN5_TX_C_DP<84>")
		)
	)
	(footprint ""
		(layer "F.Cu")
		(at 336.042 -154.686)
		(property "Reference" "R4788"
			(at 0 0 0)
			(layer "F.SilkS")
			(hide yes)
			(effects
				(font
					(size 1.27 1.27)
				)
			)
		)
		(property "Value" ""
			(at 0 0 0)
			(layer "F.Fab")
			(effects
				(font
					(size 1.27 1.27)
				)
			)
		)
		(duplicate_pad_numbers_are_jumpers no)
		(fp_line
			(start -0.7874 -0.4064)
			(end 0.7874 -0.4064)
			(stroke
				(width 0.1524)
				(type default)
			)
			(layer "F.SilkS")
		)
		(fp_line
			(start -0.7874 0.4064)
			(end -0.7874 -0.4064)
			(stroke
				(width 0.1524)
				(type default)
			)
			(layer "F.SilkS")
		)
		(fp_line
			(start 0.7874 -0.4064)
			(end 0.7874 0.4064)
			(stroke
				(width 0.1524)
				(type default)
			)
			(layer "F.SilkS")
		)
		(fp_line
			(start 0.7874 0.4064)
			(end -0.7874 0.4064)
			(stroke
				(width 0.1524)
				(type default)
			)
			(layer "F.SilkS")
		)
		(fp_line
			(start -0.67945 -0.305054)
			(end -0.12065 -0.305054)
			(stroke
				(width 0.1)
				(type default)
			)
			(layer "F.Fab")
		)
		(fp_line
			(start -0.67945 0.3048)
			(end -0.67945 -0.305054)
			(stroke
				(width 0.1)
				(type default)
			)
			(layer "F.Fab")
		)
		(fp_line
			(start -0.12065 -0.305054)
			(end -0.12065 -0.2794)
			(stroke
				(width 0.1)
				(type default)
			)
			(layer "F.Fab")
		)
		(fp_line
			(start -0.12065 -0.2794)
			(end 0.12065 -0.2794)
			(stroke
				(width 0.1)
				(type default)
			)
			(layer "F.Fab")
		)
		(fp_line
			(start -0.12065 0.2794)
			(end -0.12065 0.3048)
			(stroke
				(width 0.1)
				(type default)
			)
			(layer "F.Fab")
		)
		(fp_line
			(start -0.12065 0.3048)
			(end -0.67945 0.3048)
			(stroke
				(width 0.1)
				(type default)
			)
			(layer "F.Fab")
		)
		(fp_line
			(start 0.120396 0.2794)
			(end -0.12065 0.2794)
			(stroke
				(width 0.1)
				(type default)
			)
			(layer "F.Fab")
		)
		(fp_line
			(start 0.120396 0.3048)
			(end 0.120396 0.2794)
			(stroke
				(width 0.1)
				(type default)
			)
			(layer "F.Fab")
		)
		(fp_line
			(start 0.12065 -0.3048)
			(end 0.67945 -0.3048)
			(stroke
				(width 0.1)
				(type default)
			)
			(layer "F.Fab")
		)
		(fp_line
			(start 0.12065 -0.2794)
			(end 0.12065 -0.3048)
			(stroke
				(width 0.1)
				(type default)
			)
			(layer "F.Fab")
		)
		(fp_line
			(start 0.67945 -0.3048)
			(end 0.67945 0.3048)
			(stroke
				(width 0.1)
				(type default)
			)
			(layer "F.Fab")
		)
		(fp_line
			(start 0.67945 0.3048)
			(end 0.120396 0.3048)
			(stroke
				(width 0.1)
				(type default)
			)
			(layer "F.Fab")
		)
		(pad "1" smd circle
			(at -0.40005 0)
			(size 0 0)
			(layers "F.Cu" "F.Mask" "F.Paste")
			(net "P3V3_AUX")
		)
		(pad "2" smd circle
			(at 0.40005 0)
			(size 0 0)
			(layers "F.Cu" "F.Mask" "F.Paste")
			(net "SSD13_PEX_PWR_EN_R")
		)
	)
)
